(kicad_pcb
	(version 20260206)
	(generator "pcbnew")
	(generator_version "10.0")
	(general
		(thickness 1.6)
		(legacy_teardrops no)
	)
	(paper "A4")
	(title_block
		(title "v1-tray-backplane — T6M_tray_BP_c_1023_1120.brd")
		(comment 1 "Open CloudServer (Microsoft) / footprint 139 of 170 (J25), pads 1-54 of 54")
	)
	(layers
		(0 "F.Cu" signal "TOP")
		(4 "In1.Cu" signal "GND")
		(6 "In2.Cu" signal "IN1")
		(8 "In3.Cu" signal "VCC")
		(10 "In4.Cu" signal "VCC1")
		(12 "In5.Cu" signal "IN2")
		(14 "In6.Cu" signal "GND1")
		(2 "B.Cu" signal "BOTTOM")
		(9 "F.Adhes" user "F.Adhesive")
		(11 "B.Adhes" user "B.Adhesive")
		(13 "F.Paste" user "Package Geometry/Pastemask Top")
		(15 "B.Paste" user "Package Geometry/Pastemask Bottom")
		(5 "F.SilkS" user "Ref Des/Silkscreen Top")
		(7 "B.SilkS" user "Ref Des/Silkscreen Bottom")
		(1 "F.Mask" user "Board Geometry/Soldermask Top")
		(3 "B.Mask" user "Board Geometry/Soldermask Bottom")
		(17 "Dwgs.User" user "User.Drawings")
		(19 "Cmts.User" user "User.Comments")
		(21 "Eco1.User" user "User.Eco1")
		(23 "Eco2.User" user "User.Eco2")
		(25 "Edge.Cuts" user "Board Geometry/Outline")
		(27 "Margin" user)
		(31 "F.CrtYd" user "Package Geometry/Place Bound Top")
		(29 "B.CrtYd" user "Package Geometry/Place Bound Bottom")
		(35 "F.Fab" user "Ref Des/Assembly Top")
		(33 "B.Fab" user "Ref Des/Assembly Bottom")
	)
	(footprint ""
		(layer "F.Cu")
		(at 174.889922 -2.100072 180)
		(property "Reference" "J25"
			(at -4.842002 -1.120394 90)
			(unlocked yes)
			(layer "F.SilkS")
			(effects
				(font
					(size 0.7874 0.5842)
					(thickness 0.1524)
				)
				(justify left)
			)
		)
		(property "Value" ""
			(at 0 0 180)
			(layer "F.Fab")
			(effects
				(font
					(size 1.27 1.27)
				)
			)
		)
		(duplicate_pad_numbers_are_jumpers no)
		(pad "A1" thru_hole rect
			(at 0 0)
			(size 0.9144 0.9144)
			(drill 0.508)
			(layers "*.Cu" "*.Mask")
			(remove_unused_layers no)
			(net "SAS_BLAD1_TX1_P")
			(clearance 0.0508)
			(thermal_gap 0.0508)
			(padstack
				(mode front_inner_back)
				(layer "Inner"
					(shape circle)
					(size 0.9144 0.9144)
					(clearance 0.0508)
				)
				(layer "B.Cu"
					(shape rect)
					(size 0.9144 0.9144)
					(clearance 0.0508)
				)
			)
		)
		(pad "A2" thru_hole circle
			(at 1.999996 -0.100076)
			(size 0.9144 0.9144)
			(drill 0.508)
			(layers "*.Cu" "*.Mask")
			(remove_unused_layers no)
			(net "GND")
			(clearance 0.0508)
			(thermal_gap 0.0508)
		)
		(pad "A3" thru_hole circle
			(at 3.999992 0)
			(size 0.9144 0.9144)
			(drill 0.508)
			(layers "*.Cu" "*.Mask")
			(remove_unused_layers no)
			(net "AIRMAX_RSVD3")
			(clearance 0.0508)
			(thermal_gap 0.0508)
		)
		(pad "A4" thru_hole circle
			(at 5.999988 -0.100076)
			(size 0.9144 0.9144)
			(drill 0.508)
			(layers "*.Cu" "*.Mask")
			(remove_unused_layers no)
			(net "GND")
			(clearance 0.0508)
			(thermal_gap 0.0508)
		)
		(pad "A5" thru_hole circle
			(at 7.999984 0)
			(size 0.9144 0.9144)
			(drill 0.508)
			(layers "*.Cu" "*.Mask")
			(remove_unused_layers no)
			(net "SAS_BLAD1_TX6_P")
			(clearance 0.0508)
			(thermal_gap 0.0508)
		)
		(pad "A6" thru_hole circle
			(at 9.99998 -0.100076)
			(size 0.9144 0.9144)
			(drill 0.508)
			(layers "*.Cu" "*.Mask")
			(remove_unused_layers no)
			(net "GND")
			(clearance 0.0508)
			(thermal_gap 0.0508)
		)
		(pad "B1" thru_hole circle
			(at 0 1.400048)
			(size 0.9144 0.9144)
			(drill 0.508)
			(layers "*.Cu" "*.Mask")
			(remove_unused_layers no)
			(net "SAS_BLAD1_TX1_N")
			(clearance 0.0508)
			(thermal_gap 0.0508)
		)
		(pad "B2" thru_hole circle
			(at 1.999996 1.299972)
			(size 0.9144 0.9144)
			(drill 0.508)
			(layers "*.Cu" "*.Mask")
			(remove_unused_layers no)
			(net "SAS_BLAD1_RX3_P")
			(clearance 0.0508)
			(thermal_gap 0.0508)
		)
		(pad "B3" thru_hole circle
			(at 3.999992 1.400048)
			(size 0.9144 0.9144)
			(drill 0.508)
			(layers "*.Cu" "*.Mask")
			(remove_unused_layers no)
			(net "AIRMAX_RSVD4")
			(clearance 0.0508)
			(thermal_gap 0.0508)
		)
		(pad "B4" thru_hole circle
			(at 5.999988 1.299972)
			(size 0.9144 0.9144)
			(drill 0.508)
			(layers "*.Cu" "*.Mask")
			(remove_unused_layers no)
			(net "AIRMAX_RSVD1")
			(clearance 0.0508)
			(thermal_gap 0.0508)
		)
		(pad "B5" thru_hole circle
			(at 7.999984 1.400048)
			(size 0.9144 0.9144)
			(drill 0.508)
			(layers "*.Cu" "*.Mask")
			(remove_unused_layers no)
			(net "SAS_BLAD1_TX6_N")
			(clearance 0.0508)
			(thermal_gap 0.0508)
		)
		(pad "B6" thru_hole circle
			(at 9.99998 1.299972)
			(size 0.9144 0.9144)
			(drill 0.508)
			(layers "*.Cu" "*.Mask")
			(remove_unused_layers no)
			(net "SAS_BLAD1_RX8_P")
			(clearance 0.0508)
			(thermal_gap 0.0508)
		)
		(pad "C1" thru_hole circle
			(at 0 2.800096)
			(size 0.9144 0.9144)
			(drill 0.508)
			(layers "*.Cu" "*.Mask")
			(remove_unused_layers no)
			(net "GND")
			(clearance 0.0508)
			(thermal_gap 0.0508)
		)
		(pad "C2" thru_hole circle
			(at 1.999996 2.70002)
			(size 0.9144 0.9144)
			(drill 0.508)
			(layers "*.Cu" "*.Mask")
			(remove_unused_layers no)
			(net "SAS_BLAD1_RX3_N")
			(clearance 0.0508)
			(thermal_gap 0.0508)
		)
		(pad "C3" thru_hole circle
			(at 3.999992 2.800096)
			(size 0.9144 0.9144)
			(drill 0.508)
			(layers "*.Cu" "*.Mask")
			(remove_unused_layers no)
			(net "GND")
			(clearance 0.0508)
			(thermal_gap 0.0508)
		)
		(pad "C4" thru_hole circle
			(at 5.999988 2.70002)
			(size 0.9144 0.9144)
			(drill 0.508)
			(layers "*.Cu" "*.Mask")
			(remove_unused_layers no)
			(net "AIRMAX_RSVD2")
			(clearance 0.0508)
			(thermal_gap 0.0508)
		)
		(pad "C5" thru_hole circle
			(at 7.999984 2.800096)
			(size 0.9144 0.9144)
			(drill 0.508)
			(layers "*.Cu" "*.Mask")
			(remove_unused_layers no)
			(net "GND")
			(clearance 0.0508)
			(thermal_gap 0.0508)
		)
		(pad "C6" thru_hole circle
			(at 9.99998 2.70002)
			(size 0.9144 0.9144)
			(drill 0.508)
			(layers "*.Cu" "*.Mask")
			(remove_unused_layers no)
			(net "SAS_BLAD1_RX8_N")
			(clearance 0.0508)
			(thermal_gap 0.0508)
		)
		(pad "D1" thru_hole circle
			(at 0 4.19989)
			(size 0.9144 0.9144)
			(drill 0.508)
			(layers "*.Cu" "*.Mask")
			(remove_unused_layers no)
			(net "SAS_BLAD1_RX1_P")
			(clearance 0.0508)
			(thermal_gap 0.0508)
		)
		(pad "D2" thru_hole circle
			(at 1.999996 4.100068)
			(size 0.9144 0.9144)
			(drill 0.508)
			(layers "*.Cu" "*.Mask")
			(remove_unused_layers no)
			(net "GND")
			(clearance 0.0508)
			(thermal_gap 0.0508)
		)
		(pad "D3" thru_hole circle
			(at 3.999992 4.19989)
			(size 0.9144 0.9144)
			(drill 0.508)
			(layers "*.Cu" "*.Mask")
			(remove_unused_layers no)
			(net "SAS_BLAD1_RX4_P")
			(clearance 0.0508)
			(thermal_gap 0.0508)
		)
		(pad "D4" thru_hole circle
			(at 5.999988 4.100068)
			(size 0.9144 0.9144)
			(drill 0.508)
			(layers "*.Cu" "*.Mask")
			(remove_unused_layers no)
			(net "GND")
			(clearance 0.0508)
			(thermal_gap 0.0508)
		)
		(pad "D5" thru_hole circle
			(at 7.999984 4.19989)
			(size 0.9144 0.9144)
			(drill 0.508)
			(layers "*.Cu" "*.Mask")
			(remove_unused_layers no)
			(net "SAS_BLAD1_RX6_P")
			(clearance 0.0508)
			(thermal_gap 0.0508)
		)
		(pad "D6" thru_hole circle
			(at 9.99998 4.100068)
			(size 0.9144 0.9144)
			(drill 0.508)
			(layers "*.Cu" "*.Mask")
			(remove_unused_layers no)
			(net "GND")
			(clearance 0.0508)
			(thermal_gap 0.0508)
		)
		(pad "E1" thru_hole circle
			(at 0 5.599938)
			(size 0.9144 0.9144)
			(drill 0.508)
			(layers "*.Cu" "*.Mask")
			(remove_unused_layers no)
			(net "SAS_BLAD1_RX1_N")
			(clearance 0.0508)
			(thermal_gap 0.0508)
		)
		(pad "E2" thru_hole circle
			(at 1.999996 5.500116)
			(size 0.9144 0.9144)
			(drill 0.508)
			(layers "*.Cu" "*.Mask")
			(remove_unused_layers no)
			(net "SAS_BLAD1_TX3_P")
			(clearance 0.0508)
			(thermal_gap 0.0508)
		)
		(pad "E3" thru_hole circle
			(at 3.999992 5.599938)
			(size 0.9144 0.9144)
			(drill 0.508)
			(layers "*.Cu" "*.Mask")
			(remove_unused_layers no)
			(net "SAS_BLAD1_RX4_N")
			(clearance 0.0508)
			(thermal_gap 0.0508)
		)
		(pad "E4" thru_hole circle
			(at 5.999988 5.500116)
			(size 0.9144 0.9144)
			(drill 0.508)
			(layers "*.Cu" "*.Mask")
			(remove_unused_layers no)
			(net "SAS_BLAD1_TX5_P")
			(clearance 0.0508)
			(thermal_gap 0.0508)
		)
		(pad "E5" thru_hole circle
			(at 7.999984 5.599938)
			(size 0.9144 0.9144)
			(drill 0.508)
			(layers "*.Cu" "*.Mask")
			(remove_unused_layers no)
			(net "SAS_BLAD1_RX6_N")
			(clearance 0.0508)
			(thermal_gap 0.0508)
		)
		(pad "E6" thru_hole circle
			(at 9.99998 5.500116)
			(size 0.9144 0.9144)
			(drill 0.508)
			(layers "*.Cu" "*.Mask")
			(remove_unused_layers no)
			(net "SAS_BLAD1_TX8_P")
			(clearance 0.0508)
			(thermal_gap 0.0508)
		)
		(pad "F1" thru_hole circle
			(at 0 6.999986)
			(size 0.9144 0.9144)
			(drill 0.508)
			(layers "*.Cu" "*.Mask")
			(remove_unused_layers no)
			(net "GND")
			(clearance 0.0508)
			(thermal_gap 0.0508)
		)
		(pad "F2" thru_hole circle
			(at 1.999996 6.89991)
			(size 0.9144 0.9144)
			(drill 0.508)
			(layers "*.Cu" "*.Mask")
			(remove_unused_layers no)
			(net "SAS_BLAD1_TX3_N")
			(clearance 0.0508)
			(thermal_gap 0.0508)
		)
		(pad "F3" thru_hole circle
			(at 3.999992 6.999986)
			(size 0.9144 0.9144)
			(drill 0.508)
			(layers "*.Cu" "*.Mask")
			(remove_unused_layers no)
			(net "GND")
			(clearance 0.0508)
			(thermal_gap 0.0508)
		)
		(pad "F4" thru_hole circle
			(at 5.999988 6.89991)
			(size 0.9144 0.9144)
			(drill 0.508)
			(layers "*.Cu" "*.Mask")
			(remove_unused_layers no)
			(net "SAS_BLAD1_TX5_N")
			(clearance 0.0508)
			(thermal_gap 0.0508)
		)
		(pad "F5" thru_hole circle
			(at 7.999984 6.999986)
			(size 0.9144 0.9144)
			(drill 0.508)
			(layers "*.Cu" "*.Mask")
			(remove_unused_layers no)
			(net "GND")
			(clearance 0.0508)
			(thermal_gap 0.0508)
		)
		(pad "F6" thru_hole circle
			(at 9.99998 6.89991)
			(size 0.9144 0.9144)
			(drill 0.508)
			(layers "*.Cu" "*.Mask")
			(remove_unused_layers no)
			(net "SAS_BLAD1_TX8_N")
			(clearance 0.0508)
			(thermal_gap 0.0508)
		)
		(pad "G1" thru_hole circle
			(at 0 8.400034)
			(size 0.9144 0.9144)
			(drill 0.508)
			(layers "*.Cu" "*.Mask")
			(remove_unused_layers no)
			(net "SAS_BLAD1_TX2_P")
			(clearance 0.0508)
			(thermal_gap 0.0508)
		)
		(pad "G2" thru_hole circle
			(at 1.999996 8.299958)
			(size 0.9144 0.9144)
			(drill 0.508)
			(layers "*.Cu" "*.Mask")
			(remove_unused_layers no)
			(net "GND")
			(clearance 0.0508)
			(thermal_gap 0.0508)
		)
		(pad "G3" thru_hole circle
			(at 3.999992 8.400034)
			(size 0.9144 0.9144)
			(drill 0.508)
			(layers "*.Cu" "*.Mask")
			(remove_unused_layers no)
			(net "SAS_BLAD1_TX4_P")
			(clearance 0.0508)
			(thermal_gap 0.0508)
		)
		(pad "G4" thru_hole circle
			(at 5.999988 8.299958)
			(size 0.9144 0.9144)
			(drill 0.508)
			(layers "*.Cu" "*.Mask")
			(remove_unused_layers no)
			(net "GND")
			(clearance 0.0508)
			(thermal_gap 0.0508)
		)
		(pad "G5" thru_hole circle
			(at 7.999984 8.400034)
			(size 0.9144 0.9144)
			(drill 0.508)
			(layers "*.Cu" "*.Mask")
			(remove_unused_layers no)
			(net "SAS_BLAD1_TX7_P")
			(clearance 0.0508)
			(thermal_gap 0.0508)
		)
		(pad "G6" thru_hole circle
			(at 9.99998 8.299958)
			(size 0.9144 0.9144)
			(drill 0.508)
			(layers "*.Cu" "*.Mask")
			(remove_unused_layers no)
			(net "GND")
			(clearance 0.0508)
			(thermal_gap 0.0508)
		)
		(pad "H1" thru_hole circle
			(at 0 9.800082)
			(size 0.9144 0.9144)
			(drill 0.508)
			(layers "*.Cu" "*.Mask")
			(remove_unused_layers no)
			(net "SAS_BLAD1_TX2_N")
			(clearance 0.0508)
			(thermal_gap 0.0508)
		)
		(pad "H2" thru_hole circle
			(at 1.999996 9.700006)
			(size 0.9144 0.9144)
			(drill 0.508)
			(layers "*.Cu" "*.Mask")
			(remove_unused_layers no)
			(net "SAS_BLAD1_RX2_P")
			(clearance 0.0508)
			(thermal_gap 0.0508)
		)
		(pad "H3" thru_hole circle
			(at 3.999992 9.800082)
			(size 0.9144 0.9144)
			(drill 0.508)
			(layers "*.Cu" "*.Mask")
			(remove_unused_layers no)
			(net "SAS_BLAD1_TX4_N")
			(clearance 0.0508)
			(thermal_gap 0.0508)
		)
		(pad "H4" thru_hole circle
			(at 5.999988 9.700006)
			(size 0.9144 0.9144)
			(drill 0.508)
			(layers "*.Cu" "*.Mask")
			(remove_unused_layers no)
			(net "SAS_BLAD1_RX5_P")
			(clearance 0.0508)
			(thermal_gap 0.0508)
		)
		(pad "H5" thru_hole circle
			(at 7.999984 9.800082)
			(size 0.9144 0.9144)
			(drill 0.508)
			(layers "*.Cu" "*.Mask")
			(remove_unused_layers no)
			(net "SAS_BLAD1_TX7_N")
			(clearance 0.0508)
			(thermal_gap 0.0508)
		)
		(pad "H6" thru_hole circle
			(at 9.99998 9.700006)
			(size 0.9144 0.9144)
			(drill 0.508)
			(layers "*.Cu" "*.Mask")
			(remove_unused_layers no)
			(net "SAS_BLAD1_RX7_P")
			(clearance 0.0508)
			(thermal_gap 0.0508)
		)
		(pad "I1" thru_hole circle
			(at 0 11.199876)
			(size 0.9144 0.9144)
			(drill 0.508)
			(layers "*.Cu" "*.Mask")
			(remove_unused_layers no)
			(net "GND")
			(clearance 0.0508)
			(thermal_gap 0.0508)
		)
		(pad "I2" thru_hole circle
			(at 1.999996 11.100054)
			(size 0.9144 0.9144)
			(drill 0.508)
			(layers "*.Cu" "*.Mask")
			(remove_unused_layers no)
			(net "SAS_BLAD1_RX2_N")
			(clearance 0.0508)
			(thermal_gap 0.0508)
		)
		(pad "I3" thru_hole circle
			(at 3.999992 11.199876)
			(size 0.9144 0.9144)
			(drill 0.508)
			(layers "*.Cu" "*.Mask")
			(remove_unused_layers no)
			(net "GND")
			(clearance 0.0508)
			(thermal_gap 0.0508)
		)
		(pad "I4" thru_hole circle
			(at 5.999988 11.100054)
			(size 0.9144 0.9144)
			(drill 0.508)
			(layers "*.Cu" "*.Mask")
			(remove_unused_layers no)
			(net "SAS_BLAD1_RX5_N")
			(clearance 0.0508)
			(thermal_gap 0.0508)
		)
		(pad "I5" thru_hole circle
			(at 7.999984 11.199876)
			(size 0.9144 0.9144)
			(drill 0.508)
			(layers "*.Cu" "*.Mask")
			(remove_unused_layers no)
			(net "GND")
			(clearance 0.0508)
			(thermal_gap 0.0508)
		)
		(pad "I6" thru_hole circle
			(at 9.99998 11.100054)
			(size 0.9144 0.9144)
			(drill 0.508)
			(layers "*.Cu" "*.Mask")
			(remove_unused_layers no)
			(net "SAS_BLAD1_RX7_N")
			(clearance 0.0508)
			(thermal_gap 0.0508)
		)
	)
)
